FILE_TYPE=LIBRARY_PARTS;
primitive 'LMV331IDCKRG4-GP';
  pin
    '+IN':
      PIN_NUMBER='(1)';
      INPUT_LOAD='(-0.01,0.01)';
    '-IN':
      PIN_NUMBER='(3)';
      INPUT_LOAD='(-0.01,0.01)';
    'OUT':
      PIN_NUMBER='(4)';
      OUTPUT_LOAD='(1.0,-1.0)';
    'VCC':
      PIN_NUMBER='(5)';
      PINUSE='POWER';
      NO_LOAD_CHECK='Both';
      NO_IO_CHECK='Both';
      NO_ASSERT_CHECK='TRUE';
      NO_DIR_CHECK='TRUE';
      ALLOW_CONNECT='TRUE';
    'GND':
      PIN_NUMBER='(2)';
      PINUSE='POWER';
      NO_LOAD_CHECK='Both';
      NO_IO_CHECK='Both';
      NO_ASSERT_CHECK='TRUE';
      NO_DIR_CHECK='TRUE';
      ALLOW_CONNECT='TRUE';
  end_pin;
  body
    PART_NAME='LMV331IDCKRG4-GP';
    BODY_NAME='LMV331IDCKRG4-GP';
    PHYS_DES_PREFIX='U';
    CLASS='DISCRETE';
  end_body;
end_primitive;

END.
